# S9S_MB_2U (Grand Teton) — schematic netlist excerpt (pin names and nets, part order shuffled) for the footprints in the layout excerpt that follows; sources: Cadence DE-HDL packaged netlist, KiCad conversion of 03242023_DA0F0TMBIJ0_F0T_Motherboard_J_brd_V01_OCP.brd

J31  SCONN288_ADR50017P130CC  SCONN288_ADR50017-P130CC IO  pkg DDR288S_1-1VXB  page 112
  VIN_BULK0  = P12V_S3_AUX_CPU1_NVDIMM
  RFU0  = TP_CHH_CPU1_DIMM1_FRU_0
  VIN_MGMT  = P3V3_AUX
  HSCL  = I3C_SPD_DDREFGH_CPU1_LVC1_SCL_6
  HSDA  = I3C_SPD_DDREFGH_CPU1_LVC1_SDA
  VSS0  = GND
  DQ0_A  = M_H_CPU1_SA_DQ<0>
  VSS1  = GND
  DQ1_A  = M_H_CPU1_SA_DQ<1>
  VSS2  = GND
  DQS0_A_T  = M_H_CPU1_SA_DQS_DP<0>
  DQS0_A_C  = M_H_CPU1_SA_DQS_DN<0>
  VSS3  = GND
  DQ4_A  = M_H_CPU1_SA_DQ<4>
  VSS4  = GND
  DQ5_A  = M_H_CPU1_SA_DQ<5>
  VSS5  = GND
  DQ8_A  = M_H_CPU1_SA_DQ<8>
  VSS6  = GND
  DQ9_A  = M_H_CPU1_SA_DQ<9>
  VSS7  = GND
  DQS1_A_T  = M_H_CPU1_SA_DQS_DP<1>
  DQS1_A_C  = M_H_CPU1_SA_DQS_DN<1>
  VSS8  = GND
  DQ12_A  = M_H_CPU1_SA_DQ<12>
  VSS9  = GND
  DQ13_A  = M_H_CPU1_SA_DQ<13>
  VSS10  = GND
  DQ16_A  = M_H_CPU1_SA_DQ<16>
  VSS11  = GND
  DQ17_A  = M_H_CPU1_SA_DQ<17>
  VSS12  = GND
  DQS2_A_T  = M_H_CPU1_SA_DQS_DP<2>
  DQS2_A_C  = M_H_CPU1_SA_DQS_DN<2>
  VSS13  = GND
  DQ20_A  = M_H_CPU1_SA_DQ<20>
  VSS14  = GND
  DQ21_A  = M_H_CPU1_SA_DQ<21>
  VSS15  = GND
  DQ24_A  = M_H_CPU1_SA_DQ<24>
  VSS16  = GND
  DQ25_A  = M_H_CPU1_SA_DQ<25>
  VSS17  = GND
  DQS3_A_T  = M_H_CPU1_SA_DQS_DP<3>
  DQS3_A_C  = M_H_CPU1_SA_DQS_DN<3>
  VSS18  = GND
  DQ28_A  = M_H_CPU1_SA_DQ<28>
  VSS19  = GND
  DQ29_A  = M_H_CPU1_SA_DQ<29>
  VSS20  = GND
  CB0_A  = M_H_CPU1_SA_CB<0>
  VSS21  = GND
  CB1_A  = M_H_CPU1_SA_CB<1>
  VSS22  = GND
  DQS4_A_T  = M_H_CPU1_SA_DQS_DP<4>
  DQS4_A_C  = M_H_CPU1_SA_DQS_DN<4>
  VSS23  = GND
  CB4_A  = M_H_CPU1_SA_CB<4>
  VSS24  = GND
  CB5_A  = M_H_CPU1_SA_CB<5>
  VSS25  = GND
  ALERT_N  = M_H_CPU1_ALERT_N
  VSS26  = GND
  CS0_A_N  = M_H_CPU1_SA_CS_N<0>
  VSS27  = GND
  CA0_A  = M_H_CPU1_SA_CA<0>
  VSS28  = GND
  CA2_A  = M_H_CPU1_SA_CA<2>
  VSS29  = GND
  CA4_A  = M_H_CPU1_SA_CA<4>
  VSS30  = GND
  CA6_A  = M_H_CPU1_SA_CA<6>
  VSS31  = GND
  PAR_A  = M_H_CPU1_SA_PAR
  VSS32  = GND
  CA0_B  = M_H_CPU1_SB_CA<0>
  VSS33  = GND
  CA2_B  = M_H_CPU1_SB_CA<2>
  VSS34  = GND
  CA4_B  = M_H_CPU1_SB_CA<4>
  VSS35  = GND
  CA6_B  = M_H_CPU1_SB_CA<6>
  VSS36  = GND
  CS0_B_N  = M_H_CPU1_SB_CS_N<0>
  VSS37  = GND
  \lbd||rsp_a_n\  = M_H_CPU1_SA_RSP<0>
  \lbs||rsp_b_n\  = M_H_CPU1_SB_RSP<0>
  VSS38  = GND
  CB4_B  = M_H_CPU1_SB_CB<4>
  VSS39  = GND
  CB5_B  = M_H_CPU1_SB_CB<5>
  VSS40  = GND
  \dqs9_b_t||tdqs9_b_t||dbi4_b_n\  = M_H_CPU1_SB_DQS_DP<9>
  \dqs9_b_c||tdqs9_b_c\  = M_H_CPU1_SB_DQS_DN<9>
  VSS41  = GND
  CB0_B  = M_H_CPU1_SB_CB<0>
  VSS42  = GND
  CB1_B  = M_H_CPU1_SB_CB<1>
  VSS43  = GND
  DQ0_B  = M_H_CPU1_SB_DQ<0>
  VSS44  = GND
  DQ1_B  = M_H_CPU1_SB_DQ<1>
  VSS45  = GND
  DQS0_B_T  = M_H_CPU1_SB_DQS_DP<0>
  DQS0_B_C  = M_H_CPU1_SB_DQS_DN<0>
  VSS46  = GND
  DQ4_B  = M_H_CPU1_SB_DQ<4>
  VSS47  = GND
  DQ5_B  = M_H_CPU1_SB_DQ<5>
  VSS48  = GND
  DQ8_B  = M_H_CPU1_SB_DQ<8>
  VSS49  = GND
  DQ9_B  = M_H_CPU1_SB_DQ<9>
  VSS50  = GND
  DQS1_B_T  = M_H_CPU1_SB_DQS_DP<1>
  DQS1_B_C  = M_H_CPU1_SB_DQS_DN<1>
  VSS51  = GND
  DQ12_B  = M_H_CPU1_SB_DQ<12>
  VSS52  = GND
  DQ13_B  = M_H_CPU1_SB_DQ<13>
  VSS53  = GND
  DQ16_B  = M_H_CPU1_SB_DQ<16>
  VSS54  = GND
  DQ17_B  = M_H_CPU1_SB_DQ<17>
  VSS55  = GND
  DQS2_B_T  = M_H_CPU1_SB_DQS_DP<2>
  DQS2_B_C  = M_H_CPU1_SB_DQS_DN<2>
  VSS56  = GND
  DQ20_B  = M_H_CPU1_SB_DQ<20>
  VSS57  = GND
  DQ21_B  = M_H_CPU1_SB_DQ<21>
  VSS58  = GND
  DQ24_B  = M_H_CPU1_SB_DQ<24>
  VSS59  = GND
  DQ25_B  = M_H_CPU1_SB_DQ<25>
  VSS60  = GND
  DQS3_B_T  = M_H_CPU1_SB_DQS_DP<3>
  DQS3_B_C  = M_H_CPU1_SB_DQS_DN<3>
  VSS61  = GND
  DQ28_B  = M_H_CPU1_SB_DQ<28>
  VSS62  = GND
  DQ29_B  = M_H_CPU1_SB_DQ<29>
  VSS63  = GND
  RFU1  = TP_CHH_CPU1_DIMM1_FRU_1
  VIN_BULK1  = P12V_S3_AUX_CPU1_NVDIMM
  VIN_BULK2  = P12V_S3_AUX_CPU1_NVDIMM
  \pwr_good||fail_n\  = PWRGD_CHH_CPU1_DIMM1
  HSA  = PD_CHH_CPU1_DIMM1_SAA
  RFU2  = TP_CHH_CPU1_DIMM1_FRU_2
  RFU3  = TP_CHH_CPU1_DIMM1_FRU_3
  VSS64  = GND
  DQ2_A  = M_H_CPU1_SA_DQ<2>
  VSS65  = GND
  DQ3_A  = M_H_CPU1_SA_DQ<3>
  VSS66  = GND
  \dqs5_a_c||tdqs5_a_c||dqs5_a_t||tdqs5_a_t\  = M_H_CPU1_SA_DQS_DN<5>
  \dqs5_a_t||tdqs5_a_t\  = M_H_CPU1_SA_DQS_DP<5>
  VSS67  = GND
  DQ6_A  = M_H_CPU1_SA_DQ<6>
  VSS68  = GND
  DQ7_A  = M_H_CPU1_SA_DQ<7>
  VSS69  = GND
  DQ10_A  = M_H_CPU1_SA_DQ<10>
  VSS70  = GND
  DQ11_A  = M_H_CPU1_SA_DQ<11>
  VSS71  = GND
  \dqs6_a_c||tdqs6_a_c||dqs6_a_t||tdqs6_a_t\  = M_H_CPU1_SA_DQS_DN<6>
  \dqs6_a_t||tdqs6_a_t\  = M_H_CPU1_SA_DQS_DP<6>
  VSS72  = GND
  DQ14_A  = M_H_CPU1_SA_DQ<14>
  VSS73  = GND
  DQ15_A  = M_H_CPU1_SA_DQ<15>
  VSS74  = GND
  DQ18_A  = M_H_CPU1_SA_DQ<18>
  VSS75  = GND
  DQ19_A  = M_H_CPU1_SA_DQ<19>
  VSS76  = GND
  \dqs7_a_c||tdqs7_a_c\  = M_H_CPU1_SA_DQS_DN<7>
  \dqs7_a_t||tdqs7_a_t\  = M_H_CPU1_SA_DQS_DP<7>
  VSS77  = GND
  DQ22_A  = M_H_CPU1_SA_DQ<22>
  VSS78  = GND
  DQ23_A  = M_H_CPU1_SA_DQ<23>
  VSS79  = GND
  DQ26_A  = M_H_CPU1_SA_DQ<26>
  VSS80  = GND
  DQ27_A  = M_H_CPU1_SA_DQ<27>
  VSS81  = GND
  \dqs8_a_c||tdqs8_a_c\  = M_H_CPU1_SA_DQS_DN<8>
  \dqs8_a_t||tdqs8_a_t\  = M_H_CPU1_SA_DQS_DP<8>
  VSS82  = GND
  DQ30_A  = M_H_CPU1_SA_DQ<30>
  VSS83  = GND
  DQ31_A  = M_H_CPU1_SA_DQ<31>
  VSS84  = GND
  CB2_A  = M_H_CPU1_SA_CB<2>
  VSS85  = GND
  CB3_A  = M_H_CPU1_SA_CB<3>
  VSS86  = GND
  \dqs9_a_c||tdqs9_a_c\  = M_H_CPU1_SA_DQS_DN<9>
  \dqs9_a_t||tdqs9_a_t\  = M_H_CPU1_SA_DQS_DP<9>
  VSS87  = GND
  CB6_A  = M_H_CPU1_SA_CB<6>
  VSS88  = GND
  CB7_A  = M_H_CPU1_SA_CB<7>
  VSS89  = GND
  RESET_N  = RST_M_GH_CPU1_FPGA_N
  VSS90  = GND
  CS1_A_N  = M_H_CPU1_SA_CS_N<1>
  VSS91  = GND
  CA1_A  = M_H_CPU1_SA_CA<1>
  VSS92  = GND
  CA3_A  = M_H_CPU1_SA_CA<3>
  VSS93  = GND
  CA5_A  = M_H_CPU1_SA_CA<5>
  VSS94  = GND
  CK_T  = M_H_CPU1_CLK_DP<0>
  CK_C  = M_H_CPU1_CLK_DN<0>
  VSS95  = GND
  RFU4  = TP_CHH_CPU1_DIMM1_FRU_4
  CA1_B  = M_H_CPU1_SB_CA<1>
  VSS96  = GND
  CA3_B  = M_H_CPU1_SB_CA<3>
  VSS97  = GND
  CA5_B  = M_H_CPU1_SB_CA<5>
  VSS98  = GND
  PAR_B  = M_H_CPU1_SB_PAR
  VSS99  = GND
  CS1_B_N  = M_H_CPU1_SB_CS_N<1>
  VSS100  = GND
  RFU5  = TP_CHH_CPU1_DIMM1_FRU_5
  RFU6  = TP_CHH_CPU1_DIMM1_FRU_6
  VSS101  = GND
  CB6_B  = M_H_CPU1_SB_CB<6>
  VSS102  = GND
  CB7_B  = M_H_CPU1_SB_CB<7>
  VSS103  = GND
  DQS4_B_C  = M_H_CPU1_SB_DQS_DN<4>
  DQS4_B_T  = M_H_CPU1_SB_DQS_DP<4>
  VSS104  = GND
  CB2_B  = M_H_CPU1_SB_CB<2>
  VSS105  = GND
  CB3_B  = M_H_CPU1_SB_CB<3>
  VSS106  = GND
  DQ2_B  = M_H_CPU1_SB_DQ<2>
  VSS107  = GND
  DQ3_B  = M_H_CPU1_SB_DQ<3>
  VSS108  = GND
  \dqs5_b_c||tdqs5_b_c\  = M_H_CPU1_SB_DQS_DN<5>
  \dqs5_b_t||tdqs5_b_t\  = M_H_CPU1_SB_DQS_DP<5>
  VSS109  = GND
  DQ6_B  = M_H_CPU1_SB_DQ<6>
  VSS110  = GND
  DQ7_B  = M_H_CPU1_SB_DQ<7>
  VSS111  = GND
  DQ10_B  = M_H_CPU1_SB_DQ<10>
  VSS112  = GND
  DQ11_B  = M_H_CPU1_SB_DQ<11>
  VSS113  = GND
  \dqs6_b_c||tdqs6_b_c\  = M_H_CPU1_SB_DQS_DN<6>
  \dqs6_b_t||tdqs6_b_t\  = M_H_CPU1_SB_DQS_DP<6>
  VSS114  = GND
  DQ14_B  = M_H_CPU1_SB_DQ<14>
  VSS115  = GND
  DQ15_B  = M_H_CPU1_SB_DQ<15>
  VSS116  = GND
  DQ18_B  = M_H_CPU1_SB_DQ<18>
  VSS117  = GND
  DQ19_B  = M_H_CPU1_SB_DQ<19>
  VSS118  = GND
  \dqs7_b_c||tdqs7_b_c\  = M_H_CPU1_SB_DQS_DN<7>
  \dqs7_b_t||tdqs7_b_t\  = M_H_CPU1_SB_DQS_DP<7>
  VSS119  = GND
  DQ22_B  = M_H_CPU1_SB_DQ<22>
  VSS120  = GND
  DQ23_B  = M_H_CPU1_SB_DQ<23>
  VSS121  = GND
  DQ26_B  = M_H_CPU1_SB_DQ<26>
  VSS122  = GND
  DQ27_B  = M_H_CPU1_SB_DQ<27>
  VSS123  = GND
  \dqs8_b_c||tdqs8_b_c\  = M_H_CPU1_SB_DQS_DN<8>
  \dqs8_b_t||tdqs8_b_t\  = M_H_CPU1_SB_DQS_DP<8>
  VSS124  = GND
  DQ30_B  = M_H_CPU1_SB_DQ<30>
  VSS125  = GND
  DQ31_B  = M_H_CPU1_SB_DQ<31>
  VSS126  = GND
  G1  = GND
  G2  = GND
  G3  = GND

(kicad_pcb
	(version 20260206)
	(generator "pcbnew")
	(generator_version "10.0")
	(general
		(thickness 1.6)
		(legacy_teardrops no)
	)
	(paper "A4")
	(title_block
		(title "03242023_DA0F0TMBIJ0_F0T_Motherboard_J_brd_V01_OCP.brd")
		(comment 1 "Grand Teton / footprint 3900 of 6105 (J31), pads 275-291 of 291")
	)
	(layers
		(0 "F.Cu" signal "TOP")
		(4 "In1.Cu" signal "GND")
		(6 "In2.Cu" signal "IN1")
		(8 "In3.Cu" signal "GND1")
		(10 "In4.Cu" signal "IN2")
		(12 "In5.Cu" signal "GND2")
		(14 "In6.Cu" signal "IN3")
		(16 "In7.Cu" signal "GND3")
		(18 "In8.Cu" signal "VCC")
		(20 "In9.Cu" signal "VCC1")
		(22 "In10.Cu" signal "GND4")
		(24 "In11.Cu" signal "IN4")
		(26 "In12.Cu" signal "GND5")
		(28 "In13.Cu" signal "IN5")
		(30 "In14.Cu" signal "GND6")
		(32 "In15.Cu" signal "IN6")
		(34 "In16.Cu" signal "GND7")
		(2 "B.Cu" signal "BOTTOM")
		(9 "F.Adhes" user "F.Adhesive")
		(11 "B.Adhes" user "B.Adhesive")
		(13 "F.Paste" user "Package Geometry/Pastemask Top")
		(15 "B.Paste" user "Package Geometry/Pastemask Bottom")
		(5 "F.SilkS" user "Ref Des/Silkscreen Top")
		(7 "B.SilkS" user "Ref Des/Silkscreen Bottom")
		(1 "F.Mask" user "Board Geometry/Soldermask Top")
		(3 "B.Mask" user "Board Geometry/Soldermask Bottom")
		(17 "Dwgs.User" user "User.Drawings")
		(19 "Cmts.User" user "User.Comments")
		(21 "Eco1.User" user "User.Eco1")
		(23 "Eco2.User" user "User.Eco2")
		(25 "Edge.Cuts" user "Board Geometry/Outline")
		(27 "Margin" user)
		(31 "F.CrtYd" user "Package Geometry/Place Bound Top")
		(29 "B.CrtYd" user "Package Geometry/Place Bound Bottom")
		(35 "F.Fab" user "Ref Des/Assembly Top")
		(33 "B.Fab" user "Ref Des/Assembly Bottom")
	)
	(footprint ""
		(layer "F.Cu")
		(at 213.66988 -258.091686)
		(property "Reference" "J31"
			(at -3.683 -81.702148 0)
			(unlocked yes)
			(layer "F.SilkS")
			(effects
				(font
					(size 0.7874 0.5842)
					(thickness 0.1524)
				)
				(justify left)
			)
		)
		(property "Value" ""
			(at 0 0 0)
			(layer "F.Fab")
			(effects
				(font
					(size 1.27 1.27)
				)
			)
		)
		(duplicate_pad_numbers_are_jumpers no)
		(pad "275" smd rect
			(at 2.050034 52.274978 270)
			(size 0.519938 1.4986)
			(layers "F.Cu" "F.Mask" "F.Paste")
			(net "GND")
		)
		(pad "276" smd rect
			(at 2.050034 53.125116 270)
			(size 0.519938 1.4986)
			(layers "F.Cu" "F.Mask" "F.Paste")
			(net "M_H_CPU1_SB_DQ<23>")
		)
		(pad "277" smd rect
			(at 2.050034 53.975 270)
			(size 0.519938 1.4986)
			(layers "F.Cu" "F.Mask" "F.Paste")
			(net "GND")
		)
		(pad "278" smd rect
			(at 2.050034 54.824884 270)
			(size 0.519938 1.4986)
			(layers "F.Cu" "F.Mask" "F.Paste")
			(net "M_H_CPU1_SB_DQ<26>")
		)
		(pad "279" smd rect
			(at 2.050034 55.675022 270)
			(size 0.519938 1.4986)
			(layers "F.Cu" "F.Mask" "F.Paste")
			(net "GND")
		)
		(pad "280" smd rect
			(at 2.050034 56.524906 270)
			(size 0.519938 1.4986)
			(layers "F.Cu" "F.Mask" "F.Paste")
			(net "M_H_CPU1_SB_DQ<27>")
		)
		(pad "281" smd rect
			(at 2.050034 57.375044 270)
			(size 0.519938 1.4986)
			(layers "F.Cu" "F.Mask" "F.Paste")
			(net "GND")
		)
		(pad "282" smd rect
			(at 2.050034 58.224928 270)
			(size 0.519938 1.4986)
			(layers "F.Cu" "F.Mask" "F.Paste")
			(net "M_H_CPU1_SB_DQS_DN<8>")
		)
		(pad "283" smd rect
			(at 2.050034 59.075066 270)
			(size 0.519938 1.4986)
			(layers "F.Cu" "F.Mask" "F.Paste")
			(net "M_H_CPU1_SB_DQS_DP<8>")
		)
		(pad "284" smd rect
			(at 2.050034 59.92495 270)
			(size 0.519938 1.4986)
			(layers "F.Cu" "F.Mask" "F.Paste")
			(net "GND")
		)
		(pad "285" smd rect
			(at 2.050034 60.775088 270)
			(size 0.519938 1.4986)
			(layers "F.Cu" "F.Mask" "F.Paste")
			(net "M_H_CPU1_SB_DQ<30>")
		)
		(pad "286" smd rect
			(at 2.050034 61.624972 270)
			(size 0.519938 1.4986)
			(layers "F.Cu" "F.Mask" "F.Paste")
			(net "GND")
		)
		(pad "287" smd rect
			(at 2.050034 62.47511 270)
			(size 0.519938 1.4986)
			(layers "F.Cu" "F.Mask" "F.Paste")
			(net "M_H_CPU1_SB_DQ<31>")
		)
		(pad "288" smd rect
			(at 2.050034 63.324994 270)
			(size 0.519938 1.4986)
			(layers "F.Cu" "F.Mask" "F.Paste")
			(net "GND")
		)
		(pad "G1" thru_hole oval
			(at 0 -68.97497)
			(size 2.8194 1.5748)
			(drill oval 2.4384 1.1938)
			(layers "*.Cu" "*.Mask")
			(remove_unused_layers no)
			(net "GND")
			(clearance 0.127)
			(thermal_gap 0.127)
		)
		(pad "G2" thru_hole oval
			(at 0 3.875024)
			(size 2.8194 1.5748)
			(drill oval 2.4384 1.1938)
			(layers "*.Cu" "*.Mask")
			(remove_unused_layers no)
			(net "GND")
			(clearance 0.127)
			(thermal_gap 0.127)
		)
		(pad "G3" thru_hole oval
			(at 0 68.97497)
			(size 2.8194 1.5748)
			(drill oval 2.4384 1.1938)
			(layers "*.Cu" "*.Mask")
			(remove_unused_layers no)
			(net "GND")
			(clearance 0.127)
			(thermal_gap 0.127)
		)
	)
)
